# S9S_MB_2U (Grand Teton) — schematic parts with pin connectivity, parts 5876–5876 of 6093; source: Cadence DE-HDL packaged netlist (pstxprt.dat, pstxnet.dat, pstchip.dat)

U1  SOCKET4677_AZIF0045P001C01CS  SOCKET4677_AZIF0045-P001C01CS IO  pkg SOCKET4677_82X64-5XA_H466  page 44  (pins 3271-3597 of 4677)
  DY53  DDR5_SA_DQ31  BI  = M_F_CPU1_SA_DQ<31>
  DY55  DDR5_SA_DQS_DP8  BI  = M_F_CPU1_SA_DQS_DP<8>
  DY57  DDR5_SA_DQ26  BI  = M_F_CPU1_SA_DQ<26>
  DY59  DDR6_SA_DQ23  BI  = M_G_CPU1_SA_DQ<23>
  DY61  DDR6_SA_DQS_DP7  BI  = M_G_CPU1_SA_DQS_DP<7>
  DY63  DDR6_SA_DQ18  BI  = M_G_CPU1_SA_DQ<18>
  DY65  DDR5_SA_DQ15  BI  = M_F_CPU1_SA_DQ<15>
  DY67  DDR5_SA_DQS_DP6  BI  = M_F_CPU1_SA_DQS_DP<6>
  DY69  DDR5_SA_DQ10  BI  = M_F_CPU1_SA_DQ<10>
  DY71  DDR6_SA_DQ7  BI  = M_G_CPU1_SA_DQ<7>
  DY73  DDR6_SA_DQS_DP5  BI  = M_G_CPU1_SA_DQS_DP<5>
  DY75  DDR6_SA_DQ2  BI  = M_G_CPU1_SA_DQ<2>
  DY77  VSS1269  POWER  = GND
  DY79  DDR7_SA_DQ0  BI  = M_H_CPU1_SA_DQ<0>
  DY81  UPI3_RX_DN8  IN  = GND
  DY83  UPI3_RX_DP7  IN  = GND
  DY85  VCCFA_EHV_FIVRA65  POWER  = PVCCFA_EHV_FIVRA_CPU1
  DY87  PE3_TX_DN2  OUT  = P5E_CPU1_PE3_TX_DN<2>
  DY89  VCCFA_EHV_FIVRA66  POWER  = PVCCFA_EHV_FIVRA_CPU1
  DY91  PE3_RX_DN3  IN  = P5E_CPU1_PE3_RX_DN<3>
  E5  VSS1125  POWER  = GND
  E7  DDR0_SB_DQ31  BI  = M_A_CPU1_SB_DQ<31>
  E9  DDR0_SB_DQS_DP8  BI  = M_A_CPU1_SB_DQS_DP<8>
  E11  DDR0_SB_DQ26  BI  = M_A_CPU1_SB_DQ<26>
  E13  DDR1_SB_DQ29  BI  = M_B_CPU1_SB_DQ<29>
  E15  DDR1_SB_DQS_DN8  BI  = M_B_CPU1_SB_DQS_DN<8>
  E17  DDR1_SB_DQ26  BI  = M_B_CPU1_SB_DQ<26>
  E19  DDR0_SB_DQ23  BI  = M_A_CPU1_SB_DQ<23>
  E21  DDR0_SB_DQS_DP7  BI  = M_A_CPU1_SB_DQS_DP<7>
  E23  DDR0_SB_DQ18  BI  = M_A_CPU1_SB_DQ<18>
  E25  DDR0_SB_DQ15  BI  = M_A_CPU1_SB_DQ<15>
  E27  DDR0_SB_DQS_DP6  BI  = M_A_CPU1_SB_DQS_DP<6>
  E29  DDR0_SB_DQ10  BI  = M_A_CPU1_SB_DQ<10>
  E31  DDR0_SB_ECC3  BI  = M_A_CPU1_SB_CB<3>
  E33  DDR0_SB_DQS_DP4  BI  = M_A_CPU1_SB_DQS_DP<4>
  E35  DDR0_SB_ECC6  BI  = M_A_CPU1_SB_CB<6>
  E37  DDR0_SB_CS_N3  OUT  = M_A_CPU1_SB_CS_N<3>
  E39  VSS1271  POWER  = GND
  E41  DDR0_SB_CA3  OUT  = M_A_CPU1_SB_CA<3>
  E43  DDR0_SB_CA0  OUT  = M_A_CPU1_SB_CA<0>
  E45  DDR0_CLK_DP1  OUT  = M_A_CPU1_CLK_DP<1>
  E48  DDR0_SA_PAR  OUT  = M_A_CPU1_SA_PAR
  E50  DDR0_SA_CA5  OUT  = M_A_CPU1_SA_CA<5>
  E52  VSS1126  POWER  = GND
  E54  DDR0_SA_CS_N2  OUT  = M_A_CPU1_SA_CS_N<2>
  E56  DDR0_SA_ECC7  BI  = M_A_CPU1_SA_CB<7>
  E58  DDR0_SA_DQS_DP9  BI  = M_A_CPU1_SA_DQS_DP<9>
  E60  DDR0_SA_ECC2  BI  = M_A_CPU1_SA_CB<2>
  E62  DDR0_SA_DQ31  BI  = M_A_CPU1_SA_DQ<31>
  E64  DDR0_SA_DQS_DP8  BI  = M_A_CPU1_SA_DQS_DP<8>
  E66  DDR0_SA_DQ26  BI  = M_A_CPU1_SA_DQ<26>
  E68  DDR0_SA_DQ23  BI  = M_A_CPU1_SA_DQ<23>
  E70  DDR0_SA_DQS_DP7  BI  = M_A_CPU1_SA_DQS_DP<7>
  E72  DDR0_SA_DQ17  BI  = M_A_CPU1_SA_DQ<17>
  E74  VSS1129  POWER  = GND
  E76  VSS1272  POWER  = GND
  E78  VSS1131  POWER  = GND
  E80  UPI2_RX_DN0  IN  = UPI_CPU0_CPU1_P2P2_DN<0>
  E82  UPI2_RX_DP1  IN  = UPI_CPU0_CPU1_P2P2_DP<1>
  E84  UPI2_TX_DN1  OUT  = UPI_CPU1_CPU0_P2P2_DN<1>
  E86  VSS1273  POWER  = GND
  E88  UPI2_TX_DP2  OUT  = UPI_CPU1_CPU0_P2P2_DP<2>
  EA1  UPI1_RX_DN3  IN  = UPI_CPU0_CPU1_P0P1_DN<3>
  EA3  VCCFA_EHV_FIVRA69  POWER  = PVCCFA_EHV_FIVRA_CPU1
  EA5  UPI1_TX_DP2  OUT  = UPI_CPU1_CPU0_P1P0_DP<2>
  EA7  VCCFA_EHV_FIVRA70  POWER  = PVCCFA_EHV_FIVRA_CPU1
  EA9  PE2_RX_DN12  IN  = P5E_CPU1_PE2_RX_DN<12>
  EA11  VCCFA_EHV_FIVRA67  POWER  = PVCCFA_EHV_FIVRA_CPU1
  EA13  PE2_TX_DN12  OUT  = P5E_CPU1_PE2_TX_DN<12>
  EA15  VCCFA_EHV_FIVRA68  POWER  = PVCCFA_EHV_FIVRA_CPU1
  EA17  DDR5_SB_DQ28  BI  = M_F_CPU1_SB_DQ<28>
  EA19  DDR5_SB_DQ27  BI  = M_F_CPU1_SB_DQ<27>
  EA21  VSS1274  POWER  = GND
  EA23  DDR6_SB_DQ22  BI  = M_G_CPU1_SB_DQ<22>
  EA25  DDR6_SB_DQ19  BI  = M_G_CPU1_SB_DQ<19>
  EA27  VSS1275  POWER  = GND
  EA29  DDR5_SB_DQ6  BI  = M_F_CPU1_SB_DQ<6>
  EA31  DDR5_SB_DQ3  BI  = M_F_CPU1_SB_DQ<3>
  EA33  VSS1278  POWER  = GND
  EA35  DDR6_SB_ECC2  BI  = M_G_CPU1_SB_CB<2>
  EA37  DDR6_SB_ECC7  BI  = M_G_CPU1_SB_CB<7>
  EA39  VSS1141  POWER  = GND
  EA41  DDR6_SB_CS_N0  OUT  = M_G_CPU1_SB_CS_N<0>
  EA43  DDR6_SB_CA5  OUT  = M_G_CPU1_SB_CA<5>
  EA45  VSS1142  POWER  = GND
  EA48  DDR6_A_RSP0  IN  = M_G_CPU1_SA_RSP<0>
  EA50  DDR5_SA_PAR  OUT  = M_F_CPU1_SA_PAR
  EA52  VSS1144  POWER  = GND
  EA54  DDR5_SA_DQ30  BI  = M_F_CPU1_SA_DQ<30>
  EA56  DDR5_SA_DQ27  BI  = M_F_CPU1_SA_DQ<27>
  EA58  VSS1145  POWER  = GND
  EA60  DDR6_SA_DQ22  BI  = M_G_CPU1_SA_DQ<22>
  EA62  DDR6_SA_DQ19  BI  = M_G_CPU1_SA_DQ<19>
  EA64  VSS1146  POWER  = GND
  EA66  DDR5_SA_DQ14  BI  = M_F_CPU1_SA_DQ<14>
  EA68  DDR5_SA_DQ11  BI  = M_F_CPU1_SA_DQ<11>
  EA70  VSS1279  POWER  = GND
  EA72  DDR6_SA_DQ6  BI  = M_G_CPU1_SA_DQ<6>
  EA74  DDR6_SA_DQ3  BI  = M_G_CPU1_SA_DQ<3>
  EA76  VSS1280  POWER  = GND
  EA78  VSS1281  POWER  = GND
  EA80  VSS1282  POWER  = GND
  EA82  UPI3_RX_DN7  IN  = GND
  EA84  VSS1285  POWER  = GND
  EA86  PE3_TX_DP2  OUT  = P5E_CPU1_PE3_TX_DP<2>
  EA88  VSS1286  POWER  = GND
  EA90  PE3_RX_DP3  IN  = P5E_CPU1_PE3_RX_DP<3>
  EB2  UPI1_RX_DP3  IN  = UPI_CPU0_CPU1_P0P1_DP<3>
  EB4  VSS1163  POWER  = GND
  EB6  UPI1_TX_DN2  OUT  = UPI_CPU1_CPU0_P1P0_DN<2>
  EB8  VSS1306  POWER  = GND
  EB10  PE2_RX_DP12  IN  = P5E_CPU1_PE2_RX_DP<12>
  EB12  VSS1287  POWER  = GND
  EB14  PE2_TX_DN13  OUT  = P5E_CPU1_PE2_TX_DN<13>
  EB16  VSS1155  POWER  = GND
  EB18  DDR5_SB_DQS_DP8  BI  = M_F_CPU1_SB_DQS_DP<8>
  EB20  VSS1156  POWER  = GND
  EB22  VSS1288  POWER  = GND
  EB24  DDR6_SB_DQS_DN7  BI  = M_G_CPU1_SB_DQS_DN<7>
  EB26  VSS1158  POWER  = GND
  EB28  VSS1289  POWER  = GND
  EB30  DDR5_SB_DQS_DN5  BI  = M_F_CPU1_SB_DQS_DN<5>
  EB32  VSS1292  POWER  = GND
  EB34  VSS1161  POWER  = GND
  EB36  DDR6_SB_DQS_DN4  BI  = M_G_CPU1_SB_DQS_DN<4>
  EB38  VSS1293  POWER  = GND
  EB40  VSS1295  POWER  = GND
  EB42  DDR6_SB_PAR  OUT  = M_G_CPU1_SB_PAR
  EB44  VSS1165  POWER  = GND
  EB47  VSS1296  POWER  = GND
  EB49  DDR5_CLK_DP0  OUT  = M_F_CPU1_CLK_DP<0>
  EB51  VSS1167  POWER  = GND
  EB53  VSS1168  POWER  = GND
  EB55  DDR5_SA_DQS_DN8  BI  = M_F_CPU1_SA_DQS_DN<8>
  EB57  VSS1297  POWER  = GND
  EB59  VSS1170  POWER  = GND
  EB61  DDR6_SA_DQS_DN7  BI  = M_G_CPU1_SA_DQS_DN<7>
  EB63  VSS1171  POWER  = GND
  EB65  VSS1298  POWER  = GND
  EB67  DDR5_SA_DQS_DN6  BI  = M_F_CPU1_SA_DQS_DN<6>
  EB69  VSS1299  POWER  = GND
  EB71  VSS1300  POWER  = GND
  EB73  DDR6_SA_DQS_DN5  BI  = M_G_CPU1_SA_DQS_DN<5>
  EB75  VSS1301  POWER  = GND
  EB77  DDR5_SA_DQ0  BI  = M_F_CPU1_SA_DQ<0>
  EB79  VSS1304  POWER  = GND
  EB81  UPI3_RX_DP8  IN  = GND
  EB83  VSS1307  POWER  = GND
  EB85  PE3_TX_DN1  OUT  = P5E_CPU1_PE3_TX_DN<1>
  EB87  VSS1308  POWER  = GND
  EB89  PE3_RX_DP2  IN  = P5E_CPU1_PE3_RX_DP<2>
  EB91  VSS1180  POWER  = GND
  EC1  VSS1309  POWER  = GND
  EC3  UPI1_RX_DP2  IN  = UPI_CPU0_CPU1_P0P1_DP<2>
  EC5  VSS1193  POWER  = GND
  EC7  UPI1_TX_DN1  OUT  = UPI_CPU1_CPU0_P1P0_DN<1>
  EC9  VSS1337  POWER  = GND
  EC11  PE2_RX_DP13  IN  = P5E_CPU1_PE2_RX_DP<13>
  EC13  VSS1310  POWER  = GND
  EC15  PE2_TX_DP13  OUT  = P5E_CPU1_PE2_TX_DP<13>
  EC17  DDR5_SB_DQ30  BI  = M_F_CPU1_SB_DQ<30>
  EC19  VSS1311  POWER  = GND
  EC21  DDR5_SB_DQS_DP1  BI  = M_F_CPU1_SB_DQS_DP<1>
  EC23  VSS1313  POWER  = GND
  EC25  VSS1185  POWER  = GND
  EC27  DDR4_SB_DQS_DP0  BI  = M_E_CPU1_SB_DQS_DP<0>
  EC29  VSS1314  POWER  = GND
  EC31  VSS1316  POWER  = GND
  EC33  DDR5_SB_DQS_DP9  BI  = M_F_CPU1_SB_DQS_DP<9>
  EC35  VSS1188  POWER  = GND
  EC37  VSS1317  POWER  = GND
  EC39  DDR5_SB_CA6  OUT  = M_F_CPU1_SB_CA<6>
  EC41  VSS1321  POWER  = GND
  EC43  VSS1323  POWER  = GND
  EC45  DDR4_CLK_DP1  OUT  = M_E_CPU1_CLK_DP<1>
  EC48  VSS1324  POWER  = GND
  EC50  VSS1326  POWER  = GND
  EC52  DDR5_SA_CA0  OUT  = M_F_CPU1_SA_CA<0>
  EC54  VSS1195  POWER  = GND
  EC56  VSS1327  POWER  = GND
  EC58  DDR5_SA_DQS_DP4  BI  = M_F_CPU1_SA_DQS_DP<4>
  EC60  VSS1197  POWER  = GND
  EC62  VSS1198  POWER  = GND
  EC64  DDR5_SA_DQS_DN2  BI  = M_F_CPU1_SA_DQS_DN<2>
  EC66  VSS1329  POWER  = GND
  EC68  VSS1200  POWER  = GND
  EC70  DDR4_SA_DQS_DN1  BI  = M_E_CPU1_SA_DQS_DN<1>
  EC72  VSS1330  POWER  = GND
  EC74  VSS1332  POWER  = GND
  EC76  DDR5_SA_DQS_DP0  BI  = M_F_CPU1_SA_DQS_DP<0>
  EC78  VCCFA_EHV_FIVRA71  POWER  = PVCCFA_EHV_FIVRA_CPU1
  EC80  UPI3_RX_DN6  IN  = GND
  EC82  VSS1333  POWER  = GND
  EC84  VSS1335  POWER  = GND
  EC86  PE3_TX_DP1  OUT  = P5E_CPU1_PE3_TX_DP<1>
  EC88  VSS1336  POWER  = GND
  EC90  PE3_RX_DN2  IN  = P5E_CPU1_PE3_RX_DN<2>
  ED2  UPI1_RX_DN2  IN  = UPI_CPU0_CPU1_P0P1_DN<2>
  ED4  VSS1344  POWER  = GND
  ED6  UPI1_TX_DP1  OUT  = UPI_CPU1_CPU0_P1P0_DP<1>
  ED8  VSS1348  POWER  = GND
  ED10  PE2_RX_DN13  IN  = P5E_CPU1_PE2_RX_DN<13>
  ED12  VSS1208  POWER  = GND
  ED14  PE2_TX_DP14  OUT  = P5E_CPU1_PE2_TX_DP<14>
  ED16  VSS1338  POWER  = GND
  ED18  VSS1210  POWER  = GND
  ED20  DDR5_SB_DQ12  BI  = M_F_CPU1_SB_DQ<12>
  ED22  DDR5_SB_DQ9  BI  = M_F_CPU1_SB_DQ<9>
  ED24  VSS1339  POWER  = GND
  ED26  DDR4_SB_DQ4  BI  = M_E_CPU1_SB_DQ<4>
  ED28  DDR4_SB_DQ1  BI  = M_E_CPU1_SB_DQ<1>
  ED30  VSS1341  POWER  = GND
  ED32  DDR5_SB_ECC0  BI  = M_F_CPU1_SB_CB<0>
  ED34  DDR5_SB_ECC5  BI  = M_F_CPU1_SB_CB<5>
  ED36  VSS1342  POWER  = GND
  ED38  DDR5_SB_CS_N2  OUT  = M_F_CPU1_SB_CS_N<2>
  ED40  DDR5_SB_CA4  OUT  = M_F_CPU1_SB_CA<4>
  ED42  VSS1217  POWER  = GND
  ED44  DDR4_SA_CA6  OUT  = M_E_CPU1_SA_CA<6>
  ED47  DDR7_B_RSP1  IN  = M_H_CPU1_SB_RSP<1>
  ED49  VSS1346  POWER  = GND
  ED51  DDR5_SA_CA2  OUT  = M_F_CPU1_SA_CA<2>
  ED53  DDR5_SA_CS_N3  OUT  = M_F_CPU1_SA_CS_N<3>
  ED55  VSS1220  POWER  = GND
  ED57  DDR5_SA_ECC4  BI  = M_F_CPU1_SA_CB<4>
  ED59  DDR5_SA_ECC1  BI  = M_F_CPU1_SA_CB<1>
  ED61  VSS1223  POWER  = GND
  ED63  DDR5_SA_DQ20  BI  = M_F_CPU1_SA_DQ<20>
  ED65  DDR5_SA_DQ17  BI  = M_F_CPU1_SA_DQ<17>
  ED67  VSS1224  POWER  = GND
  ED69  DDR4_SA_DQ12  BI  = M_E_CPU1_SA_DQ<12>
  ED71  DDR4_SA_DQ9  BI  = M_E_CPU1_SA_DQ<9>
  ED73  VSS1225  POWER  = GND
  ED75  DDR5_SA_DQ4  BI  = M_F_CPU1_SA_DQ<4>
  ED77  DDR5_SA_DQ2  BI  = M_F_CPU1_SA_DQ<2>
  ED79  VCCFA_EHV_FIVRA72  POWER  = PVCCFA_EHV_FIVRA_CPU1
  ED81  UPI3_RX_DP6  IN  = GND
  ED83  UPI3_RX_DN5  IN  = GND
  ED85  VCCFA_EHV_FIVRA73  POWER  = PVCCFA_EHV_FIVRA_CPU1
  ED87  PE3_TX_DP0  OUT  = P5E_CPU1_PE3_TX_DP<0>
  ED89  VCCFA_EHV_FIVRA74  POWER  = PVCCFA_EHV_FIVRA_CPU1
  ED91  PE3_RX_DN1  IN  = P5E_CPU1_PE3_RX_DN<1>
  EE3  UPI1_RX_DN1  IN  = UPI_CPU0_CPU1_P0P1_DN<1>
  EE5  UPI1_TX_DP0  OUT  = UPI_CPU1_CPU0_P1P0_DP<0>
  EE7  VCCFA_EHV_FIVRA77  POWER  = PVCCFA_EHV_FIVRA_CPU1
  EE9  PE2_RX_DN14  IN  = P5E_CPU1_PE2_RX_DN<14>
  EE11  VCCFA_EHV_FIVRA75  POWER  = PVCCFA_EHV_FIVRA_CPU1
  EE13  PE2_TX_DN14  OUT  = P5E_CPU1_PE2_TX_DN<14>
  EE15  VCCFA_EHV_FIVRA76  POWER  = PVCCFA_EHV_FIVRA_CPU1
  EE17  VSS1232  POWER  = GND
  EE19  DDR5_SB_DQ13  BI  = M_F_CPU1_SB_DQ<13>
  EE21  DDR5_SB_DQS_DN1  BI  = M_F_CPU1_SB_DQS_DN<1>
  EE23  DDR5_SB_DQ8  BI  = M_F_CPU1_SB_DQ<8>
  EE25  DDR4_SB_DQ5  BI  = M_E_CPU1_SB_DQ<5>
  EE27  DDR4_SB_DQS_DN0  BI  = M_E_CPU1_SB_DQS_DN<0>
  EE29  DDR4_SB_DQ0  BI  = M_E_CPU1_SB_DQ<0>
  EE31  DDR5_SB_ECC1  BI  = M_F_CPU1_SB_CB<1>
  EE33  DDR5_SB_DQS_DN9  BI  = M_F_CPU1_SB_DQS_DN<9>
  EE35  DDR5_SB_ECC4  BI  = M_F_CPU1_SB_CB<4>
  EE37  DDR5_SB_CS_N3  OUT  = M_F_CPU1_SB_CS_N<3>
  EE39  VSS1235  POWER  = GND
  EE41  DDR5_SB_CA2  OUT  = M_F_CPU1_SB_CA<2>
  EE43  DDR4_SA_PAR  OUT  = M_E_CPU1_SA_PAR
  EE45  DDR4_CLK_DN1  OUT  = M_E_CPU1_CLK_DN<1>
  EE48  DDR7_B_RSP0  IN  = M_H_CPU1_SB_RSP<0>
  EE50  DDR5_SA_CA4  OUT  = M_F_CPU1_SA_CA<4>
  EE52  VSS1237  POWER  = GND
  EE54  DDR5_SA_CS_N2  OUT  = M_F_CPU1_SA_CS_N<2>
  EE56  DDR5_SA_ECC5  BI  = M_F_CPU1_SA_CB<5>
  EE58  DDR5_SA_DQS_DN4  BI  = M_F_CPU1_SA_DQS_DN<4>
  EE60  DDR5_SA_ECC0  BI  = M_F_CPU1_SA_CB<0>
  EE62  DDR5_SA_DQ21  BI  = M_F_CPU1_SA_DQ<21>
  EE64  DDR5_SA_DQS_DP2  BI  = M_F_CPU1_SA_DQS_DP<2>
  EE66  DDR5_SA_DQ16  BI  = M_F_CPU1_SA_DQ<16>
  EE68  DDR4_SA_DQ13  BI  = M_E_CPU1_SA_DQ<13>
  EE70  DDR4_SA_DQS_DP1  BI  = M_E_CPU1_SA_DQS_DP<1>
  EE72  DDR4_SA_DQ8  BI  = M_E_CPU1_SA_DQ<8>
  EE74  DDR5_SA_DQ5  BI  = M_F_CPU1_SA_DQ<5>
  EE76  DDR5_SA_DQS_DN0  BI  = M_F_CPU1_SA_DQS_DN<0>
  EE78  VSS1349  POWER  = GND
  EE80  VSS1350  POWER  = GND
  EE82  UPI3_RX_DP4  IN  = GND
  EE84  VCCFA_EHV_FIVRA78  POWER  = PVCCFA_EHV_FIVRA_CPU1
  EE86  PE3_TX_DN0  OUT  = P5E_CPU1_PE3_TX_DN<0>
  EE88  VSS1351  POWER  = GND
  EE90  PE3_RX_DP1  IN  = P5E_CPU1_PE3_RX_DP<1>
  EF2  VSS1356  POWER  = GND
  EF4  VSS1374  POWER  = GND
  EF6  UPI1_TX_DN0  OUT  = UPI_CPU1_CPU0_P1P0_DN<0>
  EF8  VSS1404  POWER  = GND
  EF10  PE2_RX_DP14  IN  = P5E_CPU1_PE2_RX_DP<14>
  EF12  VSS1352  POWER  = GND
  EF14  PE2_TX_DN15  OUT  = P5E_CPU1_PE2_TX_DN<15>
  EF16  VSS1353  POWER  = GND
  EF18  VSS1354  POWER  = GND
  EF20  VSS1358  POWER  = GND
  EF22  VSS1360  POWER  = GND
  EF24  VSS1361  POWER  = GND
  EF26  VSS1362  POWER  = GND
  EF28  VSS1363  POWER  = GND
  EF30  VSS1364  POWER  = GND
  EF32  VSS1365  POWER  = GND
  EF34  VSS1367  POWER  = GND
  EF36  VSS1370  POWER  = GND
  EF38  VSS1373  POWER  = GND
  EF40  VSS1376  POWER  = GND
  EF42  VSS1382  POWER  = GND
  EF44  VSS1383  POWER  = GND
  EF47  VSS1384  POWER  = GND
  EF49  VSS1385  POWER  = GND
  EF51  VSS1265  POWER  = GND
  EF53  VSS1386  POWER  = GND
  EF55  VSS1387  POWER  = GND
  EF57  VSS1388  POWER  = GND
  EF59  VSS1389  POWER  = GND
  EF61  VSS1390  POWER  = GND
  EF63  VSS1392  POWER  = GND
  EF65  VSS1393  POWER  = GND
  EF67  VSS1395  POWER  = GND
  EF69  VSS1399  POWER  = GND
  EF71  VSS1402  POWER  = GND
  EF73  VSS1276  POWER  = GND
  EF75  VSS1277  POWER  = GND
  EF77  VSS1403  POWER  = GND
  EF79  VCCFA_EHV_FIVRA79  POWER  = PVCCFA_EHV_FIVRA_CPU1
  EF81  UPI3_RX_DN4  IN  = GND
  EF83  UPI3_RX_DP5  IN  = GND
